(kicad_pcb
	(version 20241229)
	(generator "pcbnew")
	(generator_version "9.0")
	(general
		(thickness 1.292)
		(legacy_teardrops no)
	)
	(paper "A4")
	(title_block
		(title "LPDDR5 Testbed")
		(date "2023-12-19")
		(rev "1.0.0")
		(comment 9 "footprint 12 of 160 (U1), pads 183-274 of 315")
	)
	(layers
		(0 "F.Cu" signal)
		(4 "In1.Cu" power)
		(6 "In2.Cu" power)
		(8 "In3.Cu" signal)
		(10 "In4.Cu" signal)
		(2 "B.Cu" signal)
		(9 "F.Adhes" user "F.Adhesive")
		(11 "B.Adhes" user "B.Adhesive")
		(13 "F.Paste" user)
		(15 "B.Paste" user)
		(5 "F.SilkS" user "F.Silkscreen")
		(7 "B.SilkS" user "B.Silkscreen")
		(1 "F.Mask" user)
		(3 "B.Mask" user)
		(17 "Dwgs.User" user "User.Drawings")
		(19 "Cmts.User" user "User.Comments")
		(21 "Eco1.User" user "User.Eco1")
		(23 "Eco2.User" user "User.Eco2")
		(25 "Edge.Cuts" user)
		(27 "Margin" user)
		(31 "F.CrtYd" user "F.Courtyard")
		(29 "B.CrtYd" user "B.Courtyard")
		(35 "F.Fab" user)
		(33 "B.Fab" user)
	)
	(footprint "antmicro-footprints:BGA-315_12.4x15mm_Layout15x21_P0.8x0.7mm"
		(layer "F.Cu")
		(at 134.775 80 90)
		(property "Reference" "U1"
			(at 6.8 7.025 0)
			(unlocked yes)
			(layer "F.SilkS")
			(effects
				(font
					(size 0.7 0.7)
					(thickness 0.15)
				)
				(justify left bottom)
			)
		)
		(property "Value" "MT62F1G32D4DR-031"
			(at 0 8.9 90)
			(layer "F.Fab")
			(effects
				(font
					(size 0.7 0.7)
					(thickness 0.15)
				)
				(justify left bottom)
			)
		)
		(property "Author" "Antmicro"
			(at 214.775 -54.775 0)
			(layer "F.Fab")
			(hide yes)
			(effects
				(font
					(size 1 1)
					(thickness 0.15)
				)
			)
		)
		(property "License" "Apache-2.0"
			(at 214.775 -54.775 0)
			(layer "F.Fab")
			(hide yes)
			(effects
				(font
					(size 1 1)
					(thickness 0.15)
				)
			)
		)
		(property "MPN" "MT62F1G32D4DR-031 WT:B"
			(at 214.775 -54.775 0)
			(layer "F.Fab")
			(hide yes)
			(effects
				(font
					(size 1 1)
					(thickness 0.15)
				)
			)
		)
		(property "Manufacturer" "Micron Technology"
			(at 214.775 -54.775 0)
			(layer "F.Fab")
			(hide yes)
			(effects
				(font
					(size 1 1)
					(thickness 0.15)
				)
			)
		)
		(sheetname "LPDDR5")
		(sheetfile "lpddr5.kicad_sch")
		(attr smd)
		(pad "M3" smd circle
			(at -4 0.7 90)
			(size 0.41 0.41)
			(layers "F.Cu" "F.Mask" "F.Paste")
			(net 13 "+1V05")
			(pinfunction "VDD2H")
			(pintype "passive")
		)
		(pad "M4" smd circle
			(at -3.2 0.7 90)
			(size 0.41 0.41)
			(layers "F.Cu" "F.Mask" "F.Paste")
			(net 13 "+1V05")
			(pinfunction "VDD2H")
			(pintype "passive")
		)
		(pad "M5" smd circle
			(at -2.4 0.7 90)
			(size 0.41 0.41)
			(layers "F.Cu" "F.Mask" "F.Paste")
			(net 13 "+1V05")
			(pinfunction "VDD2H")
			(pintype "passive")
		)
		(pad "M6" smd circle
			(at -1.6 0.7 90)
			(size 0.41 0.41)
			(layers "F.Cu" "F.Mask" "F.Paste")
			(net 13 "+1V05")
			(pinfunction "VDD2H")
			(pintype "passive")
		)
		(pad "M7" smd circle
			(at -0.8 0.7 90)
			(size 0.41 0.41)
			(layers "F.Cu" "F.Mask" "F.Paste")
			(net 14 "GND")
			(pinfunction "VSS")
			(pintype "passive")
		)
		(pad "M8" smd circle
			(at 0 0.7 90)
			(size 0.41 0.41)
			(layers "F.Cu" "F.Mask" "F.Paste")
			(net 14 "GND")
			(pinfunction "VSS")
			(pintype "passive")
		)
		(pad "M9" smd circle
			(at 0.8 0.7 90)
			(size 0.41 0.41)
			(layers "F.Cu" "F.Mask" "F.Paste")
			(net 14 "GND")
			(pinfunction "VSS")
			(pintype "passive")
		)
		(pad "M10" smd circle
			(at 1.6 0.7 90)
			(size 0.41 0.41)
			(layers "F.Cu" "F.Mask" "F.Paste")
			(net 13 "+1V05")
			(pinfunction "VDD2H")
			(pintype "passive")
		)
		(pad "M11" smd circle
			(at 2.4 0.7 90)
			(size 0.41 0.41)
			(layers "F.Cu" "F.Mask" "F.Paste")
			(net 13 "+1V05")
			(pinfunction "VDD2H")
			(pintype "passive")
		)
		(pad "M12" smd circle
			(at 3.2 0.7 90)
			(size 0.41 0.41)
			(layers "F.Cu" "F.Mask" "F.Paste")
			(net 13 "+1V05")
			(pinfunction "VDD2H")
			(pintype "passive")
		)
		(pad "M13" smd circle
			(at 4 0.7 90)
			(size 0.41 0.41)
			(layers "F.Cu" "F.Mask" "F.Paste")
			(net 13 "+1V05")
			(pinfunction "VDD2H")
			(pintype "passive")
		)
		(pad "M14" smd circle
			(at 4.8 0.7 90)
			(size 0.41 0.41)
			(layers "F.Cu" "F.Mask" "F.Paste")
			(net 13 "+1V05")
			(pinfunction "VDD2H")
			(pintype "passive")
		)
		(pad "M15" smd circle
			(at 5.6 0.7 90)
			(size 0.41 0.41)
			(layers "F.Cu" "F.Mask" "F.Paste")
			(net 13 "+1V05")
			(pinfunction "VDD2H")
			(pintype "passive")
		)
		(pad "N1" smd circle
			(at -5.6 1.4 90)
			(size 0.41 0.41)
			(layers "F.Cu" "F.Mask" "F.Paste")
			(net 14 "GND")
			(pinfunction "VSS")
			(pintype "passive")
		)
		(pad "N2" smd circle
			(at -4.8 1.4 90)
			(size 0.41 0.41)
			(layers "F.Cu" "F.Mask" "F.Paste")
			(net 12 "+0V9")
			(pinfunction "VDD2L")
			(pintype "passive")
		)
		(pad "N3" smd circle
			(at -4 1.4 90)
			(size 0.41 0.41)
			(layers "F.Cu" "F.Mask" "F.Paste")
			(net 14 "GND")
			(pinfunction "VSS")
			(pintype "passive")
		)
		(pad "N4" smd circle
			(at -3.2 1.4 90)
			(size 0.41 0.41)
			(layers "F.Cu" "F.Mask" "F.Paste")
			(net 14 "GND")
			(pinfunction "VSS")
			(pintype "passive")
		)
		(pad "N5" smd circle
			(at -2.4 1.4 90)
			(size 0.41 0.41)
			(layers "F.Cu" "F.Mask" "F.Paste")
			(net 13 "+1V05")
			(pinfunction "VDD2H")
			(pintype "passive")
		)
		(pad "N6" smd circle
			(at -1.6 1.4 90)
			(size 0.41 0.41)
			(layers "F.Cu" "F.Mask" "F.Paste")
			(net 14 "GND")
			(pinfunction "VSS")
			(pintype "passive")
		)
		(pad "N7" smd circle
			(at -0.8 1.4 90)
			(size 0.41 0.41)
			(layers "F.Cu" "F.Mask" "F.Paste")
			(net 113 "/LPDDR5/LPDDR5_B.CK_N")
			(pinfunction "CK_c_B")
			(pintype "passive")
		)
		(pad "N8" smd circle
			(at 0 1.4 90)
			(size 0.41 0.41)
			(layers "F.Cu" "F.Mask" "F.Paste")
			(net 14 "GND")
			(pinfunction "VSS")
			(pintype "passive")
		)
		(pad "N9" smd circle
			(at 0.8 1.4 90)
			(size 0.41 0.41)
			(layers "F.Cu" "F.Mask" "F.Paste")
			(net 14 "GND")
			(pinfunction "VSS")
			(pintype "passive")
		)
		(pad "N10" smd circle
			(at 1.6 1.4 90)
			(size 0.41 0.41)
			(layers "F.Cu" "F.Mask" "F.Paste")
			(net 14 "GND")
			(pinfunction "VSS")
			(pintype "passive")
		)
		(pad "N11" smd circle
			(at 2.4 1.4 90)
			(size 0.41 0.41)
			(layers "F.Cu" "F.Mask" "F.Paste")
			(net 13 "+1V05")
			(pinfunction "VDD2H")
			(pintype "passive")
		)
		(pad "N12" smd circle
			(at 3.2 1.4 90)
			(size 0.41 0.41)
			(layers "F.Cu" "F.Mask" "F.Paste")
			(net 14 "GND")
			(pinfunction "VSS")
			(pintype "passive")
		)
		(pad "N13" smd circle
			(at 4 1.4 90)
			(size 0.41 0.41)
			(layers "F.Cu" "F.Mask" "F.Paste")
			(net 14 "GND")
			(pinfunction "VSS")
			(pintype "passive")
		)
		(pad "N14" smd circle
			(at 4.8 1.4 90)
			(size 0.41 0.41)
			(layers "F.Cu" "F.Mask" "F.Paste")
			(net 12 "+0V9")
			(pinfunction "VDD2L")
			(pintype "passive")
		)
		(pad "N15" smd circle
			(at 5.6 1.4 90)
			(size 0.41 0.41)
			(layers "F.Cu" "F.Mask" "F.Paste")
			(net 14 "GND")
			(pinfunction "VSS")
			(pintype "passive")
		)
		(pad "P1" smd circle
			(at -5.6 2.1 90)
			(size 0.41 0.41)
			(layers "F.Cu" "F.Mask" "F.Paste")
			(net 31 "unconnected-(U1-PadP1)")
			(pinfunction "RFU")
			(pintype "no_connect")
		)
		(pad "P2" smd circle
			(at -4.8 2.1 90)
			(size 0.41 0.41)
			(layers "F.Cu" "F.Mask" "F.Paste")
			(net 12 "+0V9")
			(pinfunction "VDD2L")
			(pintype "passive")
		)
		(pad "P3" smd circle
			(at -4 2.1 90)
			(size 0.41 0.41)
			(layers "F.Cu" "F.Mask" "F.Paste")
			(net 101 "/LPDDR5/LPDDR5_B.CA5")
			(pinfunction "CA5_B")
			(pintype "passive")
		)
		(pad "P4" smd circle
			(at -3.2 2.1 90)
			(size 0.41 0.41)
			(layers "F.Cu" "F.Mask" "F.Paste")
			(net 14 "GND")
			(pinfunction "VSS")
			(pintype "passive")
		)
		(pad "P5" smd circle
			(at -2.4 2.1 90)
			(size 0.41 0.41)
			(layers "F.Cu" "F.Mask" "F.Paste")
			(net 99 "/LPDDR5/LPDDR5_B.CA3")
			(pinfunction "CA3_B")
			(pintype "passive")
		)
		(pad "P6" smd circle
			(at -1.6 2.1 90)
			(size 0.41 0.41)
			(layers "F.Cu" "F.Mask" "F.Paste")
			(net 14 "GND")
			(pinfunction "VSS")
			(pintype "passive")
		)
		(pad "P7" smd circle
			(at -0.8 2.1 90)
			(size 0.41 0.41)
			(layers "F.Cu" "F.Mask" "F.Paste")
			(net 112 "/LPDDR5/LPDDR5_B.CK_P")
			(pinfunction "CK_t_B")
			(pintype "passive")
		)
		(pad "P8" smd circle
			(at 0 2.1 90)
			(size 0.41 0.41)
			(layers "F.Cu" "F.Mask" "F.Paste")
			(net 14 "GND")
			(pinfunction "VSS")
			(pintype "passive")
		)
		(pad "P9" smd circle
			(at 0.8 2.1 90)
			(size 0.41 0.41)
			(layers "F.Cu" "F.Mask" "F.Paste")
			(net 106 "/LPDDR5/LPDDR5_B.CS0")
			(pinfunction "CS0_B")
			(pintype "passive")
		)
		(pad "P10" smd circle
			(at 1.6 2.1 90)
			(size 0.41 0.41)
			(layers "F.Cu" "F.Mask" "F.Paste")
			(net 14 "GND")
			(pinfunction "VSS")
			(pintype "passive")
		)
		(pad "P11" smd circle
			(at 2.4 2.1 90)
			(size 0.41 0.41)
			(layers "F.Cu" "F.Mask" "F.Paste")
			(net 103 "/LPDDR5/LPDDR5_B.CA1")
			(pinfunction "CA1_B")
			(pintype "passive")
		)
		(pad "P12" smd circle
			(at 3.2 2.1 90)
			(size 0.41 0.41)
			(layers "F.Cu" "F.Mask" "F.Paste")
			(net 14 "GND")
			(pinfunction "VSS")
			(pintype "passive")
		)
		(pad "P13" smd circle
			(at 4 2.1 90)
			(size 0.41 0.41)
			(layers "F.Cu" "F.Mask" "F.Paste")
			(net 14 "GND")
			(pinfunction "VSS")
			(pintype "passive")
		)
		(pad "P14" smd circle
			(at 4.8 2.1 90)
			(size 0.41 0.41)
			(layers "F.Cu" "F.Mask" "F.Paste")
			(net 12 "+0V9")
			(pinfunction "VDD2L")
			(pintype "passive")
		)
		(pad "P15" smd circle
			(at 5.6 2.1 90)
			(size 0.41 0.41)
			(layers "F.Cu" "F.Mask" "F.Paste")
			(net 32 "unconnected-(U1-PadP15)")
			(pinfunction "RFU")
			(pintype "no_connect")
		)
		(pad "R1" smd circle
			(at -5.6 2.8 90)
			(size 0.41 0.41)
			(layers "F.Cu" "F.Mask" "F.Paste")
			(net 4 "+0V5")
			(pinfunction "VDDQ")
			(pintype "passive")
		)
		(pad "R2" smd circle
			(at -4.8 2.8 90)
			(size 0.41 0.41)
			(layers "F.Cu" "F.Mask" "F.Paste")
			(net 4 "+0V5")
			(pinfunction "VDDQ")
			(pintype "passive")
		)
		(pad "R3" smd circle
			(at -4 2.8 90)
			(size 0.41 0.41)
			(layers "F.Cu" "F.Mask" "F.Paste")
			(net 14 "GND")
			(pinfunction "VSS")
			(pintype "passive")
		)
		(pad "R4" smd circle
			(at -3.2 2.8 90)
			(size 0.41 0.41)
			(layers "F.Cu" "F.Mask" "F.Paste")
			(net 100 "/LPDDR5/LPDDR5_B.CA6")
			(pinfunction "CA6_B")
			(pintype "passive")
		)
		(pad "R5" smd circle
			(at -2.4 2.8 90)
			(size 0.41 0.41)
			(layers "F.Cu" "F.Mask" "F.Paste")
			(net 14 "GND")
			(pinfunction "VSS")
			(pintype "passive")
		)
		(pad "R6" smd circle
			(at -1.6 2.8 90)
			(size 0.41 0.41)
			(layers "F.Cu" "F.Mask" "F.Paste")
			(net 105 "/LPDDR5/LPDDR5_B.CA4")
			(pinfunction "CA4_B")
			(pintype "passive")
		)
		(pad "R7" smd circle
			(at -0.8 2.8 90)
			(size 0.41 0.41)
			(layers "F.Cu" "F.Mask" "F.Paste")
			(net 14 "GND")
			(pinfunction "VSS")
			(pintype "passive")
		)
		(pad "R8" smd circle
			(at 0 2.8 90)
			(size 0.41 0.41)
			(layers "F.Cu" "F.Mask" "F.Paste")
			(net 104 "/LPDDR5/LPDDR5_B.CA2")
			(pinfunction "CA2_B")
			(pintype "passive")
		)
		(pad "R9" smd circle
			(at 0.8 2.8 90)
			(size 0.41 0.41)
			(layers "F.Cu" "F.Mask" "F.Paste")
			(net 14 "GND")
			(pinfunction "VSS")
			(pintype "passive")
		)
		(pad "R10" smd circle
			(at 1.6 2.8 90)
			(size 0.41 0.41)
			(layers "F.Cu" "F.Mask" "F.Paste")
			(net 107 "/LPDDR5/LPDDR5_B.CS1")
			(pinfunction "CS1_B")
			(pintype "passive")
		)
		(pad "R11" smd circle
			(at 2.4 2.8 90)
			(size 0.41 0.41)
			(layers "F.Cu" "F.Mask" "F.Paste")
			(net 14 "GND")
			(pinfunction "VSS")
			(pintype "passive")
		)
		(pad "R12" smd circle
			(at 3.2 2.8 90)
			(size 0.41 0.41)
			(layers "F.Cu" "F.Mask" "F.Paste")
			(net 102 "/LPDDR5/LPDDR5_B.CA0")
			(pinfunction "CA0_B")
			(pintype "passive")
		)
		(pad "R13" smd circle
			(at 4 2.8 90)
			(size 0.41 0.41)
			(layers "F.Cu" "F.Mask" "F.Paste")
			(net 14 "GND")
			(pinfunction "VSS")
			(pintype "passive")
		)
		(pad "R14" smd circle
			(at 4.8 2.8 90)
			(size 0.41 0.41)
			(layers "F.Cu" "F.Mask" "F.Paste")
			(net 4 "+0V5")
			(pinfunction "VDDQ")
			(pintype "passive")
		)
		(pad "R15" smd circle
			(at 5.6 2.8 90)
			(size 0.41 0.41)
			(layers "F.Cu" "F.Mask" "F.Paste")
			(net 4 "+0V5")
			(pinfunction "VDDQ")
			(pintype "passive")
		)
		(pad "T1" smd circle
			(at -5.6 3.5 90)
			(size 0.41 0.41)
			(layers "F.Cu" "F.Mask" "F.Paste")
			(net 4 "+0V5")
			(pinfunction "VDDQ")
			(pintype "passive")
		)
		(pad "T2" smd circle
			(at -4.8 3.5 90)
			(size 0.41 0.41)
			(layers "F.Cu" "F.Mask" "F.Paste")
			(net 14 "GND")
			(pinfunction "VSS")
			(pintype "passive")
		)
		(pad "T3" smd circle
			(at -4 3.5 90)
			(size 0.41 0.41)
			(layers "F.Cu" "F.Mask" "F.Paste")
			(net 4 "+0V5")
			(pinfunction "VDDQ")
			(pintype "passive")
		)
		(pad "T4" smd circle
			(at -3.2 3.5 90)
			(size 0.41 0.41)
			(layers "F.Cu" "F.Mask" "F.Paste")
			(net 4 "+0V5")
			(pinfunction "VDDQ")
			(pintype "passive")
		)
		(pad "T5" smd circle
			(at -2.4 3.5 90)
			(size 0.41 0.41)
			(layers "F.Cu" "F.Mask" "F.Paste")
			(net 216 "/LPDDR5/LPDDR5_B.DQ15")
			(pinfunction "DQ15_B")
			(pintype "passive")
		)
		(pad "T6" smd circle
			(at -1.6 3.5 90)
			(size 0.41 0.41)
			(layers "F.Cu" "F.Mask" "F.Paste")
			(net 13 "+1V05")
			(pinfunction "VDD2H")
			(pintype "passive")
		)
		(pad "T7" smd circle
			(at -0.8 3.5 90)
			(size 0.41 0.41)
			(layers "F.Cu" "F.Mask" "F.Paste")
			(net 13 "+1V05")
			(pinfunction "VDD2H")
			(pintype "passive")
		)
		(pad "T8" smd circle
			(at 0 3.5 90)
			(size 0.41 0.41)
			(layers "F.Cu" "F.Mask" "F.Paste")
			(net 14 "GND")
			(pinfunction "VSS")
			(pintype "passive")
		)
		(pad "T9" smd circle
			(at 0.8 3.5 90)
			(size 0.41 0.41)
			(layers "F.Cu" "F.Mask" "F.Paste")
			(net 13 "+1V05")
			(pinfunction "VDD2H")
			(pintype "passive")
		)
		(pad "T10" smd circle
			(at 1.6 3.5 90)
			(size 0.41 0.41)
			(layers "F.Cu" "F.Mask" "F.Paste")
			(net 13 "+1V05")
			(pinfunction "VDD2H")
			(pintype "passive")
		)
		(pad "T11" smd circle
			(at 2.4 3.5 90)
			(size 0.41 0.41)
			(layers "F.Cu" "F.Mask" "F.Paste")
			(net 217 "/LPDDR5/LPDDR5_B.DQ7")
			(pinfunction "DQ7_B")
			(pintype "passive")
		)
		(pad "T12" smd circle
			(at 3.2 3.5 90)
			(size 0.41 0.41)
			(layers "F.Cu" "F.Mask" "F.Paste")
			(net 4 "+0V5")
			(pinfunction "VDDQ")
			(pintype "passive")
		)
		(pad "T13" smd circle
			(at 4 3.5 90)
			(size 0.41 0.41)
			(layers "F.Cu" "F.Mask" "F.Paste")
			(net 4 "+0V5")
			(pinfunction "VDDQ")
			(pintype "passive")
		)
		(pad "T14" smd circle
			(at 4.8 3.5 90)
			(size 0.41 0.41)
			(layers "F.Cu" "F.Mask" "F.Paste")
			(net 14 "GND")
			(pinfunction "VSS")
			(pintype "passive")
		)
		(pad "T15" smd circle
			(at 5.6 3.5 90)
			(size 0.41 0.41)
			(layers "F.Cu" "F.Mask" "F.Paste")
			(net 4 "+0V5")
			(pinfunction "VDDQ")
			(pintype "passive")
		)
		(pad "U1" smd circle
			(at -5.6 4.2 90)
			(size 0.41 0.41)
			(layers "F.Cu" "F.Mask" "F.Paste")
			(net 14 "GND")
			(pinfunction "VSS")
			(pintype "passive")
		)
		(pad "U2" smd circle
			(at -4.8 4.2 90)
			(size 0.41 0.41)
			(layers "F.Cu" "F.Mask" "F.Paste")
			(net 208 "/LPDDR5/LPDDR5_B.DQ10")
			(pinfunction "DQ10_B")
			(pintype "passive")
		)
		(pad "U3" smd circle
			(at -4 4.2 90)
			(size 0.41 0.41)
			(layers "F.Cu" "F.Mask" "F.Paste")
			(net 14 "GND")
			(pinfunction "VSS")
			(pintype "passive")
		)
		(pad "U4" smd circle
			(at -3.2 4.2 90)
			(size 0.41 0.41)
			(layers "F.Cu" "F.Mask" "F.Paste")
			(net 111 "/LPDDR5/LPDDR5_B.WCK1_P")
			(pinfunction "WCK1_t_B")
			(pintype "passive")
		)
		(pad "U5" smd circle
			(at -2.4 4.2 90)
			(size 0.41 0.41)
			(layers "F.Cu" "F.Mask" "F.Paste")
			(net 4 "+0V5")
			(pinfunction "VDDQ")
			(pintype "passive")
		)
		(pad "U6" smd circle
			(at -1.6 4.2 90)
			(size 0.41 0.41)
			(layers "F.Cu" "F.Mask" "F.Paste")
			(net 215 "/LPDDR5/LPDDR5_B.DQ14")
			(pinfunction "DQ14_B")
			(pintype "passive")
		)
		(pad "U7" smd circle
			(at -0.8 4.2 90)
			(size 0.41 0.41)
			(layers "F.Cu" "F.Mask" "F.Paste")
			(net 13 "+1V05")
			(pinfunction "VDD2H")
			(pintype "passive")
		)
		(pad "U8" smd circle
			(at 0 4.2 90)
			(size 0.41 0.41)
			(layers "F.Cu" "F.Mask" "F.Paste")
			(net 14 "GND")
			(pinfunction "VSS")
			(pintype "passive")
		)
		(pad "U9" smd circle
			(at 0.8 4.2 90)
			(size 0.41 0.41)
			(layers "F.Cu" "F.Mask" "F.Paste")
			(net 13 "+1V05")
			(pinfunction "VDD2H")
			(pintype "passive")
		)
		(pad "U10" smd circle
			(at 1.6 4.2 90)
			(size 0.41 0.41)
			(layers "F.Cu" "F.Mask" "F.Paste")
			(net 218 "/LPDDR5/LPDDR5_B.DQ6")
			(pinfunction "DQ6_B")
			(pintype "passive")
		)
		(pad "U11" smd circle
			(at 2.4 4.2 90)
			(size 0.41 0.41)
			(layers "F.Cu" "F.Mask" "F.Paste")
			(net 4 "+0V5")
			(pinfunction "VDDQ")
			(pintype "passive")
		)
		(pad "U12" smd circle
			(at 3.2 4.2 90)
			(size 0.41 0.41)
			(layers "F.Cu" "F.Mask" "F.Paste")
			(net 108 "/LPDDR5/LPDDR5_B.WCK0_P")
			(pinfunction "WCK0_t_B")
			(pintype "passive")
		)
		(pad "U13" smd circle
			(at 4 4.2 90)
			(size 0.41 0.41)
			(layers "F.Cu" "F.Mask" "F.Paste")
			(net 14 "GND")
			(pinfunction "VSS")
			(pintype "passive")
		)
		(pad "U14" smd circle
			(at 4.8 4.2 90)
			(size 0.41 0.41)
			(layers "F.Cu" "F.Mask" "F.Paste")
			(net 225 "/LPDDR5/LPDDR5_B.DQ2")
			(pinfunction "DQ2_B")
			(pintype "passive")
		)
		(pad "U15" smd circle
			(at 5.6 4.2 90)
			(size 0.41 0.41)
			(layers "F.Cu" "F.Mask" "F.Paste")
			(net 14 "GND")
			(pinfunction "VSS")
			(pintype "passive")
		)
		(pad "V1" smd circle
			(at -5.6 4.9 90)
			(size 0.41 0.41)
			(layers "F.Cu" "F.Mask" "F.Paste")
			(net 206 "/LPDDR5/LPDDR5_B.DQ8")
			(pinfunction "DQ8_B")
			(pintype "passive")
		)
		(pad "V2" smd circle
			(at -4.8 4.9 90)
			(size 0.41 0.41)
			(layers "F.Cu" "F.Mask" "F.Paste")
			(net 14 "GND")
			(pinfunction "VSS")
			(pintype "passive")
		)
		(pad "V3" smd circle
			(at -4 4.9 90)
			(size 0.41 0.41)
			(layers "F.Cu" "F.Mask" "F.Paste")
			(net 209 "/LPDDR5/LPDDR5_B.DQ11")
			(pinfunction "DQ11_B")
			(pintype "passive")
		)
		(pad "V4" smd circle
			(at -3.2 4.9 90)
			(size 0.41 0.41)
			(layers "F.Cu" "F.Mask" "F.Paste")
			(net 4 "+0V5")
			(pinfunction "VDDQ")
			(pintype "passive")
		)
	)
)
